(kicad_pcb
	(version 20260206)
	(generator "pcbnew")
	(generator_version "10.0")
	(general
		(thickness 1.6)
		(legacy_teardrops no)
	)
	(paper "A4")
	(title_block
		(title "03242023_DA0F0TMBIJ0_F0T_Motherboard_J_brd_V01_OCP.brd")
		(comment 1 "Grand Teton / footprints 2540-2546 of 6105")
	)
	(layers
		(0 "F.Cu" signal "TOP")
		(4 "In1.Cu" signal "GND")
		(6 "In2.Cu" signal "IN1")
		(8 "In3.Cu" signal "GND1")
		(10 "In4.Cu" signal "IN2")
		(12 "In5.Cu" signal "GND2")
		(14 "In6.Cu" signal "IN3")
		(16 "In7.Cu" signal "GND3")
		(18 "In8.Cu" signal "VCC")
		(20 "In9.Cu" signal "VCC1")
		(22 "In10.Cu" signal "GND4")
		(24 "In11.Cu" signal "IN4")
		(26 "In12.Cu" signal "GND5")
		(28 "In13.Cu" signal "IN5")
		(30 "In14.Cu" signal "GND6")
		(32 "In15.Cu" signal "IN6")
		(34 "In16.Cu" signal "GND7")
		(2 "B.Cu" signal "BOTTOM")
		(9 "F.Adhes" user "F.Adhesive")
		(11 "B.Adhes" user "B.Adhesive")
		(13 "F.Paste" user "Package Geometry/Pastemask Top")
		(15 "B.Paste" user "Package Geometry/Pastemask Bottom")
		(5 "F.SilkS" user "Ref Des/Silkscreen Top")
		(7 "B.SilkS" user "Ref Des/Silkscreen Bottom")
		(1 "F.Mask" user "Board Geometry/Soldermask Top")
		(3 "B.Mask" user "Board Geometry/Soldermask Bottom")
		(17 "Dwgs.User" user "User.Drawings")
		(19 "Cmts.User" user "User.Comments")
		(21 "Eco1.User" user "User.Eco1")
		(23 "Eco2.User" user "User.Eco2")
		(25 "Edge.Cuts" user "Board Geometry/Outline")
		(27 "Margin" user)
		(31 "F.CrtYd" user "Package Geometry/Place Bound Top")
		(29 "B.CrtYd" user "Package Geometry/Place Bound Bottom")
		(35 "F.Fab" user "Ref Des/Assembly Top")
		(33 "B.Fab" user "Ref Des/Assembly Bottom")
	)
	(footprint ""
		(layer "F.Cu")
		(at 160.83788 -120.106948 180)
		(property "Reference" "R1407"
			(at 0 0 180)
			(layer "F.SilkS")
			(hide yes)
			(effects
				(font
					(size 1.27 1.27)
				)
			)
		)
		(property "Value" ""
			(at 0 0 180)
			(layer "F.Fab")
			(effects
				(font
					(size 1.27 1.27)
				)
			)
		)
		(duplicate_pad_numbers_are_jumpers no)
		(fp_line
			(start 0.7874 0.4064)
			(end -0.7874 0.4064)
			(stroke
				(width 0.1524)
				(type default)
			)
			(layer "F.SilkS")
		)
		(fp_line
			(start 0.7874 -0.4064)
			(end 0.7874 0.4064)
			(stroke
				(width 0.1524)
				(type default)
			)
			(layer "F.SilkS")
		)
		(fp_line
			(start -0.7874 0.4064)
			(end -0.7874 -0.4064)
			(stroke
				(width 0.1524)
				(type default)
			)
			(layer "F.SilkS")
		)
		(fp_line
			(start -0.7874 -0.4064)
			(end 0.7874 -0.4064)
			(stroke
				(width 0.1524)
				(type default)
			)
			(layer "F.SilkS")
		)
		(fp_line
			(start 0.67945 0.3048)
			(end 0.120396 0.3048)
			(stroke
				(width 0.1)
				(type default)
			)
			(layer "F.Fab")
		)
		(fp_line
			(start 0.67945 -0.3048)
			(end 0.67945 0.3048)
			(stroke
				(width 0.1)
				(type default)
			)
			(layer "F.Fab")
		)
		(fp_line
			(start 0.12065 -0.2794)
			(end 0.12065 -0.3048)
			(stroke
				(width 0.1)
				(type default)
			)
			(layer "F.Fab")
		)
		(fp_line
			(start 0.12065 -0.3048)
			(end 0.67945 -0.3048)
			(stroke
				(width 0.1)
				(type default)
			)
			(layer "F.Fab")
		)
		(fp_line
			(start 0.120396 0.3048)
			(end 0.120396 0.2794)
			(stroke
				(width 0.1)
				(type default)
			)
			(layer "F.Fab")
		)
		(fp_line
			(start 0.120396 0.2794)
			(end -0.12065 0.2794)
			(stroke
				(width 0.1)
				(type default)
			)
			(layer "F.Fab")
		)
		(fp_line
			(start -0.12065 0.3048)
			(end -0.67945 0.3048)
			(stroke
				(width 0.1)
				(type default)
			)
			(layer "F.Fab")
		)
		(fp_line
			(start -0.12065 0.2794)
			(end -0.12065 0.3048)
			(stroke
				(width 0.1)
				(type default)
			)
			(layer "F.Fab")
		)
		(fp_line
			(start -0.12065 -0.2794)
			(end 0.12065 -0.2794)
			(stroke
				(width 0.1)
				(type default)
			)
			(layer "F.Fab")
		)
		(fp_line
			(start -0.12065 -0.305054)
			(end -0.12065 -0.2794)
			(stroke
				(width 0.1)
				(type default)
			)
			(layer "F.Fab")
		)
		(fp_line
			(start -0.67945 0.3048)
			(end -0.67945 -0.305054)
			(stroke
				(width 0.1)
				(type default)
			)
			(layer "F.Fab")
		)
		(fp_line
			(start -0.67945 -0.305054)
			(end -0.12065 -0.305054)
			(stroke
				(width 0.1)
				(type default)
			)
			(layer "F.Fab")
		)
		(pad "1" smd circle
			(at -0.40005 0 180)
			(size 0 0)
			(layers "F.Cu" "F.Mask" "F.Paste")
			(net "FM_PVCCINFAON_CPU0_R_EN")
		)
		(pad "2" smd circle
			(at 0.40005 0 180)
			(size 0 0)
			(layers "F.Cu" "F.Mask" "F.Paste")
			(net "GND")
		)
	)
	(footprint ""
		(layer "F.Cu")
		(at 105.315004 -244.032024 90)
		(property "Reference" "C257"
			(at 0 0 90)
			(layer "F.SilkS")
			(hide yes)
			(effects
				(font
					(size 1.27 1.27)
				)
			)
		)
		(property "Value" ""
			(at 0 0 90)
			(layer "F.Fab")
			(effects
				(font
					(size 1.27 1.27)
				)
			)
		)
		(duplicate_pad_numbers_are_jumpers no)
		(fp_line
			(start 0.7874 -0.4064)
			(end 0.7874 0.4064)
			(stroke
				(width 0.1524)
				(type default)
			)
			(layer "F.SilkS")
		)
		(fp_line
			(start -0.7874 -0.4064)
			(end 0.7874 -0.4064)
			(stroke
				(width 0.1524)
				(type default)
			)
			(layer "F.SilkS")
		)
		(fp_line
			(start 0.7874 0.4064)
			(end -0.7874 0.4064)
			(stroke
				(width 0.1524)
				(type default)
			)
			(layer "F.SilkS")
		)
		(fp_line
			(start -0.7874 0.4064)
			(end -0.7874 -0.4064)
			(stroke
				(width 0.1524)
				(type default)
			)
			(layer "F.SilkS")
		)
		(fp_line
			(start -0.12065 -0.305054)
			(end -0.12065 -0.2794)
			(stroke
				(width 0.1)
				(type default)
			)
			(layer "F.Fab")
		)
		(fp_line
			(start -0.67945 -0.305054)
			(end -0.12065 -0.305054)
			(stroke
				(width 0.1)
				(type default)
			)
			(layer "F.Fab")
		)
		(fp_line
			(start 0.67945 -0.3048)
			(end 0.67945 0.3048)
			(stroke
				(width 0.1)
				(type default)
			)
			(layer "F.Fab")
		)
		(fp_line
			(start 0.12065 -0.3048)
			(end 0.67945 -0.3048)
			(stroke
				(width 0.1)
				(type default)
			)
			(layer "F.Fab")
		)
		(fp_line
			(start 0.12065 -0.2794)
			(end 0.12065 -0.3048)
			(stroke
				(width 0.1)
				(type default)
			)
			(layer "F.Fab")
		)
		(fp_line
			(start -0.12065 -0.2794)
			(end 0.12065 -0.2794)
			(stroke
				(width 0.1)
				(type default)
			)
			(layer "F.Fab")
		)
		(fp_line
			(start 0.120396 0.2794)
			(end -0.12065 0.2794)
			(stroke
				(width 0.1)
				(type default)
			)
			(layer "F.Fab")
		)
		(fp_line
			(start -0.12065 0.2794)
			(end -0.12065 0.3048)
			(stroke
				(width 0.1)
				(type default)
			)
			(layer "F.Fab")
		)
		(fp_line
			(start 0.67945 0.3048)
			(end 0.120396 0.3048)
			(stroke
				(width 0.1)
				(type default)
			)
			(layer "F.Fab")
		)
		(fp_line
			(start 0.120396 0.3048)
			(end 0.120396 0.2794)
			(stroke
				(width 0.1)
				(type default)
			)
			(layer "F.Fab")
		)
		(fp_line
			(start -0.12065 0.3048)
			(end -0.67945 0.3048)
			(stroke
				(width 0.1)
				(type default)
			)
			(layer "F.Fab")
		)
		(fp_line
			(start -0.67945 0.3048)
			(end -0.67945 -0.305054)
			(stroke
				(width 0.1)
				(type default)
			)
			(layer "F.Fab")
		)
		(pad "1" smd circle
			(at -0.40005 0 90)
			(size 0 0)
			(layers "F.Cu" "F.Mask" "F.Paste")
			(net "PVCCIN_CPU1")
		)
		(pad "2" smd circle
			(at 0.40005 0 90)
			(size 0 0)
			(layers "F.Cu" "F.Mask" "F.Paste")
			(net "GND")
		)
	)
	(footprint ""
		(layer "F.Cu")
		(at 236.93628 -332.849728)
		(property "Reference" ""
			(at 0 0 0)
			(layer "F.SilkS")
			(hide yes)
			(effects
				(font
					(size 1.27 1.27)
				)
			)
		)
		(property "Value" ""
			(at 0 0 0)
			(layer "F.Fab")
			(effects
				(font
					(size 1.27 1.27)
				)
			)
		)
		(duplicate_pad_numbers_are_jumpers no)
		(pad "1" smd circle
			(at 0 0)
			(size 0.9906 0.9906)
			(layers "F.Cu" "F.Mask" "F.Paste")
			(net "Net_294")
		)
		(zone
			(layer "F.Cu")
			(hatch none 0.5)
			(connect_pads
				(clearance 0)
			)
			(min_thickness 0.25)
			(keepout
				(tracks not_allowed)
				(vias allowed)
				(pads allowed)
				(copperpour not_allowed)
				(footprints allowed)
			)
			(placement
				(enabled no)
				(sheetname "")
			)
			(fill
				(thermal_gap 0.5)
				(thermal_bridge_width 0.5)
				(island_removal_mode 0)
			)
			(polygon
				(pts
					(arc
						(start 238.56188 -332.849728)
						(mid 235.31068 -332.849728)
						(end 238.56188 -332.849728)
					)
				)
			)
		)
	)
	(footprint ""
		(layer "F.Cu")
		(at 440.395868 -16.700246 180)
		(property "Reference" "C1236"
			(at 0 0 180)
			(layer "F.SilkS")
			(hide yes)
			(effects
				(font
					(size 1.27 1.27)
				)
			)
		)
		(property "Value" ""
			(at 0 0 180)
			(layer "F.Fab")
			(effects
				(font
					(size 1.27 1.27)
				)
			)
		)
		(duplicate_pad_numbers_are_jumpers no)
		(fp_line
			(start 0.7874 0.4064)
			(end -0.7874 0.4064)
			(stroke
				(width 0.1524)
				(type default)
			)
			(layer "F.SilkS")
		)
		(fp_line
			(start 0.7874 -0.4064)
			(end 0.7874 0.4064)
			(stroke
				(width 0.1524)
				(type default)
			)
			(layer "F.SilkS")
		)
		(fp_line
			(start -0.7874 0.4064)
			(end -0.7874 -0.4064)
			(stroke
				(width 0.1524)
				(type default)
			)
			(layer "F.SilkS")
		)
		(fp_line
			(start -0.7874 -0.4064)
			(end 0.7874 -0.4064)
			(stroke
				(width 0.1524)
				(type default)
			)
			(layer "F.SilkS")
		)
		(fp_line
			(start 0.67945 0.3048)
			(end 0.120396 0.3048)
			(stroke
				(width 0.1)
				(type default)
			)
			(layer "F.Fab")
		)
		(fp_line
			(start 0.67945 -0.3048)
			(end 0.67945 0.3048)
			(stroke
				(width 0.1)
				(type default)
			)
			(layer "F.Fab")
		)
		(fp_line
			(start 0.12065 -0.2794)
			(end 0.12065 -0.3048)
			(stroke
				(width 0.1)
				(type default)
			)
			(layer "F.Fab")
		)
		(fp_line
			(start 0.12065 -0.3048)
			(end 0.67945 -0.3048)
			(stroke
				(width 0.1)
				(type default)
			)
			(layer "F.Fab")
		)
		(fp_line
			(start 0.120396 0.3048)
			(end 0.120396 0.2794)
			(stroke
				(width 0.1)
				(type default)
			)
			(layer "F.Fab")
		)
		(fp_line
			(start 0.120396 0.2794)
			(end -0.12065 0.2794)
			(stroke
				(width 0.1)
				(type default)
			)
			(layer "F.Fab")
		)
		(fp_line
			(start -0.12065 0.3048)
			(end -0.67945 0.3048)
			(stroke
				(width 0.1)
				(type default)
			)
			(layer "F.Fab")
		)
		(fp_line
			(start -0.12065 0.2794)
			(end -0.12065 0.3048)
			(stroke
				(width 0.1)
				(type default)
			)
			(layer "F.Fab")
		)
		(fp_line
			(start -0.12065 -0.2794)
			(end 0.12065 -0.2794)
			(stroke
				(width 0.1)
				(type default)
			)
			(layer "F.Fab")
		)
		(fp_line
			(start -0.12065 -0.305054)
			(end -0.12065 -0.2794)
			(stroke
				(width 0.1)
				(type default)
			)
			(layer "F.Fab")
		)
		(fp_line
			(start -0.67945 0.3048)
			(end -0.67945 -0.305054)
			(stroke
				(width 0.1)
				(type default)
			)
			(layer "F.Fab")
		)
		(fp_line
			(start -0.67945 -0.305054)
			(end -0.12065 -0.305054)
			(stroke
				(width 0.1)
				(type default)
			)
			(layer "F.Fab")
		)
		(pad "1" smd circle
			(at -0.40005 0 180)
			(size 0 0)
			(layers "F.Cu" "F.Mask" "F.Paste")
			(net "P12V_OCP_SFF")
		)
		(pad "2" smd circle
			(at 0.40005 0 180)
			(size 0 0)
			(layers "F.Cu" "F.Mask" "F.Paste")
			(net "GND")
		)
	)
	(footprint ""
		(layer "F.Cu")
		(at 143.433292 -92.634308 -90)
		(property "Reference" "R4393"
			(at 0 0 270)
			(layer "F.SilkS")
			(hide yes)
			(effects
				(font
					(size 1.27 1.27)
				)
			)
		)
		(property "Value" ""
			(at 0 0 270)
			(layer "F.Fab")
			(effects
				(font
					(size 1.27 1.27)
				)
			)
		)
		(duplicate_pad_numbers_are_jumpers no)
		(fp_line
			(start -0.7874 0.4064)
			(end -0.7874 -0.4064)
			(stroke
				(width 0.1524)
				(type default)
			)
			(layer "F.SilkS")
		)
		(fp_line
			(start 0.7874 0.4064)
			(end -0.7874 0.4064)
			(stroke
				(width 0.1524)
				(type default)
			)
			(layer "F.SilkS")
		)
		(fp_line
			(start -0.7874 -0.4064)
			(end 0.7874 -0.4064)
			(stroke
				(width 0.1524)
				(type default)
			)
			(layer "F.SilkS")
		)
		(fp_line
			(start 0.7874 -0.4064)
			(end 0.7874 0.4064)
			(stroke
				(width 0.1524)
				(type default)
			)
			(layer "F.SilkS")
		)
		(fp_line
			(start -0.67945 0.3048)
			(end -0.67945 -0.305054)
			(stroke
				(width 0.1)
				(type default)
			)
			(layer "F.Fab")
		)
		(fp_line
			(start -0.12065 0.3048)
			(end -0.67945 0.3048)
			(stroke
				(width 0.1)
				(type default)
			)
			(layer "F.Fab")
		)
		(fp_line
			(start 0.120396 0.3048)
			(end 0.120396 0.2794)
			(stroke
				(width 0.1)
				(type default)
			)
			(layer "F.Fab")
		)
		(fp_line
			(start 0.67945 0.3048)
			(end 0.120396 0.3048)
			(stroke
				(width 0.1)
				(type default)
			)
			(layer "F.Fab")
		)
		(fp_line
			(start -0.12065 0.2794)
			(end -0.12065 0.3048)
			(stroke
				(width 0.1)
				(type default)
			)
			(layer "F.Fab")
		)
		(fp_line
			(start 0.120396 0.2794)
			(end -0.12065 0.2794)
			(stroke
				(width 0.1)
				(type default)
			)
			(layer "F.Fab")
		)
		(fp_line
			(start -0.12065 -0.2794)
			(end 0.12065 -0.2794)
			(stroke
				(width 0.1)
				(type default)
			)
			(layer "F.Fab")
		)
		(fp_line
			(start 0.12065 -0.2794)
			(end 0.12065 -0.3048)
			(stroke
				(width 0.1)
				(type default)
			)
			(layer "F.Fab")
		)
		(fp_line
			(start 0.12065 -0.3048)
			(end 0.67945 -0.3048)
			(stroke
				(width 0.1)
				(type default)
			)
			(layer "F.Fab")
		)
		(fp_line
			(start 0.67945 -0.3048)
			(end 0.67945 0.3048)
			(stroke
				(width 0.1)
				(type default)
			)
			(layer "F.Fab")
		)
		(fp_line
			(start -0.67945 -0.305054)
			(end -0.12065 -0.305054)
			(stroke
				(width 0.1)
				(type default)
			)
			(layer "F.Fab")
		)
		(fp_line
			(start -0.12065 -0.305054)
			(end -0.12065 -0.2794)
			(stroke
				(width 0.1)
				(type default)
			)
			(layer "F.Fab")
		)
		(pad "1" smd circle
			(at -0.40005 0 270)
			(size 0 0)
			(layers "F.Cu" "F.Mask" "F.Paste")
			(net "H_CPU_ERR1_LVC2_R_N")
		)
		(pad "2" smd circle
			(at 0.40005 0 270)
			(size 0 0)
			(layers "F.Cu" "F.Mask" "F.Paste")
			(net "H_CPU_ERR1_PCH_R_N")
		)
	)
	(footprint ""
		(layer "F.Cu")
		(at 55.090314 -152.903174)
		(property "Reference" "PC2950"
			(at 0 0 0)
			(layer "F.SilkS")
			(hide yes)
			(effects
				(font
					(size 1.27 1.27)
				)
			)
		)
		(property "Value" ""
			(at 0 0 0)
			(layer "F.Fab")
			(effects
				(font
					(size 1.27 1.27)
				)
			)
		)
		(duplicate_pad_numbers_are_jumpers no)
		(fp_line
			(start -0.7874 -0.4064)
			(end 0.7874 -0.4064)
			(stroke
				(width 0.1524)
				(type default)
			)
			(layer "F.SilkS")
		)
		(fp_line
			(start -0.7874 0.4064)
			(end -0.7874 -0.4064)
			(stroke
				(width 0.1524)
				(type default)
			)
			(layer "F.SilkS")
		)
		(fp_line
			(start 0.7874 -0.4064)
			(end 0.7874 0.4064)
			(stroke
				(width 0.1524)
				(type default)
			)
			(layer "F.SilkS")
		)
		(fp_line
			(start 0.7874 0.4064)
			(end -0.7874 0.4064)
			(stroke
				(width 0.1524)
				(type default)
			)
			(layer "F.SilkS")
		)
		(fp_line
			(start -0.67945 -0.305054)
			(end -0.12065 -0.305054)
			(stroke
				(width 0.1)
				(type default)
			)
			(layer "F.Fab")
		)
		(fp_line
			(start -0.67945 0.3048)
			(end -0.67945 -0.305054)
			(stroke
				(width 0.1)
				(type default)
			)
			(layer "F.Fab")
		)
		(fp_line
			(start -0.12065 -0.305054)
			(end -0.12065 -0.2794)
			(stroke
				(width 0.1)
				(type default)
			)
			(layer "F.Fab")
		)
		(fp_line
			(start -0.12065 -0.2794)
			(end 0.12065 -0.2794)
			(stroke
				(width 0.1)
				(type default)
			)
			(layer "F.Fab")
		)
		(fp_line
			(start -0.12065 0.2794)
			(end -0.12065 0.3048)
			(stroke
				(width 0.1)
				(type default)
			)
			(layer "F.Fab")
		)
		(fp_line
			(start -0.12065 0.3048)
			(end -0.67945 0.3048)
			(stroke
				(width 0.1)
				(type default)
			)
			(layer "F.Fab")
		)
		(fp_line
			(start 0.120396 0.2794)
			(end -0.12065 0.2794)
			(stroke
				(width 0.1)
				(type default)
			)
			(layer "F.Fab")
		)
		(fp_line
			(start 0.120396 0.3048)
			(end 0.120396 0.2794)
			(stroke
				(width 0.1)
				(type default)
			)
			(layer "F.Fab")
		)
		(fp_line
			(start 0.12065 -0.3048)
			(end 0.67945 -0.3048)
			(stroke
				(width 0.1)
				(type default)
			)
			(layer "F.Fab")
		)
		(fp_line
			(start 0.12065 -0.2794)
			(end 0.12065 -0.3048)
			(stroke
				(width 0.1)
				(type default)
			)
			(layer "F.Fab")
		)
		(fp_line
			(start 0.67945 -0.3048)
			(end 0.67945 0.3048)
			(stroke
				(width 0.1)
				(type default)
			)
			(layer "F.Fab")
		)
		(fp_line
			(start 0.67945 0.3048)
			(end 0.120396 0.3048)
			(stroke
				(width 0.1)
				(type default)
			)
			(layer "F.Fab")
		)
		(pad "1" smd circle
			(at -0.40005 0)
			(size 0 0)
			(layers "F.Cu" "F.Mask" "F.Paste")
			(net "PVCCFA_EHV_CPU1_PVCC")
		)
		(pad "2" smd circle
			(at 0.40005 0)
			(size 0 0)
			(layers "F.Cu" "F.Mask" "F.Paste")
			(net "GND")
		)
	)
	(footprint ""
		(layer "F.Cu")
		(at 37.990272 -356.02418 90)
		(property "Reference" "PC1192"
			(at 0 0 90)
			(layer "F.SilkS")
			(hide yes)
			(effects
				(font
					(size 1.27 1.27)
				)
			)
		)
		(property "Value" ""
			(at 0 0 90)
			(layer "F.Fab")
			(effects
				(font
					(size 1.27 1.27)
				)
			)
		)
		(duplicate_pad_numbers_are_jumpers no)
		(fp_line
			(start 0.7874 -0.4064)
			(end 0.7874 0.4064)
			(stroke
				(width 0.1524)
				(type default)
			)
			(layer "F.SilkS")
		)
		(fp_line
			(start -0.7874 -0.4064)
			(end 0.7874 -0.4064)
			(stroke
				(width 0.1524)
				(type default)
			)
			(layer "F.SilkS")
		)
		(fp_line
			(start 0.7874 0.4064)
			(end -0.7874 0.4064)
			(stroke
				(width 0.1524)
				(type default)
			)
			(layer "F.SilkS")
		)
		(fp_line
			(start -0.7874 0.4064)
			(end -0.7874 -0.4064)
			(stroke
				(width 0.1524)
				(type default)
			)
			(layer "F.SilkS")
		)
		(fp_line
			(start -0.12065 -0.305054)
			(end -0.12065 -0.2794)
			(stroke
				(width 0.1)
				(type default)
			)
			(layer "F.Fab")
		)
		(fp_line
			(start -0.67945 -0.305054)
			(end -0.12065 -0.305054)
			(stroke
				(width 0.1)
				(type default)
			)
			(layer "F.Fab")
		)
		(fp_line
			(start 0.67945 -0.3048)
			(end 0.67945 0.3048)
			(stroke
				(width 0.1)
				(type default)
			)
			(layer "F.Fab")
		)
		(fp_line
			(start 0.12065 -0.3048)
			(end 0.67945 -0.3048)
			(stroke
				(width 0.1)
				(type default)
			)
			(layer "F.Fab")
		)
		(fp_line
			(start 0.12065 -0.2794)
			(end 0.12065 -0.3048)
			(stroke
				(width 0.1)
				(type default)
			)
			(layer "F.Fab")
		)
		(fp_line
			(start -0.12065 -0.2794)
			(end 0.12065 -0.2794)
			(stroke
				(width 0.1)
				(type default)
			)
			(layer "F.Fab")
		)
		(fp_line
			(start 0.120396 0.2794)
			(end -0.12065 0.2794)
			(stroke
				(width 0.1)
				(type default)
			)
			(layer "F.Fab")
		)
		(fp_line
			(start -0.12065 0.2794)
			(end -0.12065 0.3048)
			(stroke
				(width 0.1)
				(type default)
			)
			(layer "F.Fab")
		)
		(fp_line
			(start 0.67945 0.3048)
			(end 0.120396 0.3048)
			(stroke
				(width 0.1)
				(type default)
			)
			(layer "F.Fab")
		)
		(fp_line
			(start 0.120396 0.3048)
			(end 0.120396 0.2794)
			(stroke
				(width 0.1)
				(type default)
			)
			(layer "F.Fab")
		)
		(fp_line
			(start -0.12065 0.3048)
			(end -0.67945 0.3048)
			(stroke
				(width 0.1)
				(type default)
			)
			(layer "F.Fab")
		)
		(fp_line
			(start -0.67945 0.3048)
			(end -0.67945 -0.305054)
			(stroke
				(width 0.1)
				(type default)
			)
			(layer "F.Fab")
		)
		(pad "1" smd circle
			(at -0.40005 0 90)
			(size 0 0)
			(layers "F.Cu" "F.Mask" "F.Paste")
			(net "PVCCFA_EHV_FIVRA_CPU1_VDD4")
		)
		(pad "2" smd circle
			(at 0.40005 0 90)
			(size 0 0)
			(layers "F.Cu" "F.Mask" "F.Paste")
			(net "GND")
		)
	)
)
